(kicad_pcb
	(version 20260206)
	(generator "pcbnew")
	(generator_version "10.0")
	(general
		(thickness 1.6)
		(legacy_teardrops no)
	)
	(paper "A4")
	(title_block
		(title "01162023_DA0F0TEBIF0_F0T_Expander_BD_F_brd_V02_OCP.brd")
		(comment 1 "Grand Teton / footprints 4738-4740 of 9728")
	)
	(layers
		(0 "F.Cu" signal "TOP")
		(4 "In1.Cu" signal "GND")
		(6 "In2.Cu" signal "VCC")
		(8 "In3.Cu" signal "VCC1")
		(10 "In4.Cu" signal "GND1")
		(12 "In5.Cu" signal "IN1")
		(14 "In6.Cu" signal "GND2")
		(16 "In7.Cu" signal "IN2")
		(18 "In8.Cu" signal "GND3")
		(20 "In9.Cu" signal "IN3")
		(22 "In10.Cu" signal "GND4")
		(24 "In11.Cu" signal "IN4")
		(26 "In12.Cu" signal "GND5")
		(28 "In13.Cu" signal "IN5")
		(30 "In14.Cu" signal "GND6")
		(32 "In15.Cu" signal "IN6")
		(34 "In16.Cu" signal "GND7")
		(2 "B.Cu" signal "BOTTOM")
		(9 "F.Adhes" user "F.Adhesive")
		(11 "B.Adhes" user "B.Adhesive")
		(13 "F.Paste" user "Package Geometry/Pastemask Top")
		(15 "B.Paste" user "Package Geometry/Pastemask Bottom")
		(5 "F.SilkS" user "Ref Des/Silkscreen Top")
		(7 "B.SilkS" user "Ref Des/Silkscreen Bottom")
		(1 "F.Mask" user "Board Geometry/Soldermask Top")
		(3 "B.Mask" user "Board Geometry/Soldermask Bottom")
		(17 "Dwgs.User" user "User.Drawings")
		(19 "Cmts.User" user "User.Comments")
		(21 "Eco1.User" user "User.Eco1")
		(23 "Eco2.User" user "User.Eco2")
		(25 "Edge.Cuts" user "Board Geometry/Outline")
		(27 "Margin" user)
		(31 "F.CrtYd" user "Package Geometry/Place Bound Top")
		(29 "B.CrtYd" user "Package Geometry/Place Bound Bottom")
		(35 "F.Fab" user "Ref Des/Assembly Top")
		(33 "B.Fab" user "Ref Des/Assembly Bottom")
	)
	(footprint ""
		(layer "F.Cu")
		(at 369.24742 -20.35556)
		(property "Reference" "C3960"
			(at 0 0 0)
			(layer "F.SilkS")
			(hide yes)
			(effects
				(font
					(size 1.27 1.27)
				)
			)
		)
		(property "Value" ""
			(at 0 0 0)
			(layer "F.Fab")
			(effects
				(font
					(size 1.27 1.27)
				)
			)
		)
		(duplicate_pad_numbers_are_jumpers no)
		(fp_line
			(start -0.7874 -0.4064)
			(end 0.7874 -0.4064)
			(stroke
				(width 0.1524)
				(type default)
			)
			(layer "F.SilkS")
		)
		(fp_line
			(start -0.7874 0.4064)
			(end -0.7874 -0.4064)
			(stroke
				(width 0.1524)
				(type default)
			)
			(layer "F.SilkS")
		)
		(fp_line
			(start 0.7874 -0.4064)
			(end 0.7874 0.4064)
			(stroke
				(width 0.1524)
				(type default)
			)
			(layer "F.SilkS")
		)
		(fp_line
			(start 0.7874 0.4064)
			(end -0.7874 0.4064)
			(stroke
				(width 0.1524)
				(type default)
			)
			(layer "F.SilkS")
		)
		(fp_line
			(start -0.67945 -0.305054)
			(end -0.12065 -0.305054)
			(stroke
				(width 0.1)
				(type default)
			)
			(layer "F.Fab")
		)
		(fp_line
			(start -0.67945 0.3048)
			(end -0.67945 -0.305054)
			(stroke
				(width 0.1)
				(type default)
			)
			(layer "F.Fab")
		)
		(fp_line
			(start -0.12065 -0.305054)
			(end -0.12065 -0.2794)
			(stroke
				(width 0.1)
				(type default)
			)
			(layer "F.Fab")
		)
		(fp_line
			(start -0.12065 -0.2794)
			(end 0.12065 -0.2794)
			(stroke
				(width 0.1)
				(type default)
			)
			(layer "F.Fab")
		)
		(fp_line
			(start -0.12065 0.2794)
			(end -0.12065 0.3048)
			(stroke
				(width 0.1)
				(type default)
			)
			(layer "F.Fab")
		)
		(fp_line
			(start -0.12065 0.3048)
			(end -0.67945 0.3048)
			(stroke
				(width 0.1)
				(type default)
			)
			(layer "F.Fab")
		)
		(fp_line
			(start 0.120396 0.2794)
			(end -0.12065 0.2794)
			(stroke
				(width 0.1)
				(type default)
			)
			(layer "F.Fab")
		)
		(fp_line
			(start 0.120396 0.3048)
			(end 0.120396 0.2794)
			(stroke
				(width 0.1)
				(type default)
			)
			(layer "F.Fab")
		)
		(fp_line
			(start 0.12065 -0.3048)
			(end 0.67945 -0.3048)
			(stroke
				(width 0.1)
				(type default)
			)
			(layer "F.Fab")
		)
		(fp_line
			(start 0.12065 -0.2794)
			(end 0.12065 -0.3048)
			(stroke
				(width 0.1)
				(type default)
			)
			(layer "F.Fab")
		)
		(fp_line
			(start 0.67945 -0.3048)
			(end 0.67945 0.3048)
			(stroke
				(width 0.1)
				(type default)
			)
			(layer "F.Fab")
		)
		(fp_line
			(start 0.67945 0.3048)
			(end 0.120396 0.3048)
			(stroke
				(width 0.1)
				(type default)
			)
			(layer "F.Fab")
		)
		(pad "1" smd circle
			(at -0.40005 0)
			(size 0 0)
			(layers "F.Cu" "F.Mask" "F.Paste")
			(net "P12V_SSD12")
		)
		(pad "2" smd circle
			(at 0.40005 0)
			(size 0 0)
			(layers "F.Cu" "F.Mask" "F.Paste")
			(net "GND")
		)
	)
	(footprint ""
		(layer "F.Cu")
		(at 127.658114 -258.131564)
		(property "Reference" "C833"
			(at 0 0 0)
			(layer "F.SilkS")
			(hide yes)
			(effects
				(font
					(size 1.27 1.27)
				)
			)
		)
		(property "Value" ""
			(at 0 0 0)
			(layer "F.Fab")
			(effects
				(font
					(size 1.27 1.27)
				)
			)
		)
		(duplicate_pad_numbers_are_jumpers no)
		(fp_line
			(start -0.7874 -0.4064)
			(end 0.7874 -0.4064)
			(stroke
				(width 0.1524)
				(type default)
			)
			(layer "F.SilkS")
		)
		(fp_line
			(start -0.7874 0.4064)
			(end -0.7874 -0.4064)
			(stroke
				(width 0.1524)
				(type default)
			)
			(layer "F.SilkS")
		)
		(fp_line
			(start 0.7874 -0.4064)
			(end 0.7874 0.4064)
			(stroke
				(width 0.1524)
				(type default)
			)
			(layer "F.SilkS")
		)
		(fp_line
			(start 0.7874 0.4064)
			(end -0.7874 0.4064)
			(stroke
				(width 0.1524)
				(type default)
			)
			(layer "F.SilkS")
		)
		(fp_line
			(start -0.67945 -0.305054)
			(end -0.12065 -0.305054)
			(stroke
				(width 0.1)
				(type default)
			)
			(layer "F.Fab")
		)
		(fp_line
			(start -0.67945 0.3048)
			(end -0.67945 -0.305054)
			(stroke
				(width 0.1)
				(type default)
			)
			(layer "F.Fab")
		)
		(fp_line
			(start -0.12065 -0.305054)
			(end -0.12065 -0.2794)
			(stroke
				(width 0.1)
				(type default)
			)
			(layer "F.Fab")
		)
		(fp_line
			(start -0.12065 -0.2794)
			(end 0.12065 -0.2794)
			(stroke
				(width 0.1)
				(type default)
			)
			(layer "F.Fab")
		)
		(fp_line
			(start -0.12065 0.2794)
			(end -0.12065 0.3048)
			(stroke
				(width 0.1)
				(type default)
			)
			(layer "F.Fab")
		)
		(fp_line
			(start -0.12065 0.3048)
			(end -0.67945 0.3048)
			(stroke
				(width 0.1)
				(type default)
			)
			(layer "F.Fab")
		)
		(fp_line
			(start 0.120396 0.2794)
			(end -0.12065 0.2794)
			(stroke
				(width 0.1)
				(type default)
			)
			(layer "F.Fab")
		)
		(fp_line
			(start 0.120396 0.3048)
			(end 0.120396 0.2794)
			(stroke
				(width 0.1)
				(type default)
			)
			(layer "F.Fab")
		)
		(fp_line
			(start 0.12065 -0.3048)
			(end 0.67945 -0.3048)
			(stroke
				(width 0.1)
				(type default)
			)
			(layer "F.Fab")
		)
		(fp_line
			(start 0.12065 -0.2794)
			(end 0.12065 -0.3048)
			(stroke
				(width 0.1)
				(type default)
			)
			(layer "F.Fab")
		)
		(fp_line
			(start 0.67945 -0.3048)
			(end 0.67945 0.3048)
			(stroke
				(width 0.1)
				(type default)
			)
			(layer "F.Fab")
		)
		(fp_line
			(start 0.67945 0.3048)
			(end 0.120396 0.3048)
			(stroke
				(width 0.1)
				(type default)
			)
			(layer "F.Fab")
		)
		(pad "1" smd circle
			(at -0.40005 0)
			(size 0 0)
			(layers "F.Cu" "F.Mask" "F.Paste")
			(net "P0V8_PEX1_BVRRDY")
		)
		(pad "2" smd circle
			(at 0.40005 0)
			(size 0 0)
			(layers "F.Cu" "F.Mask" "F.Paste")
			(net "GND")
		)
	)
	(footprint ""
		(layer "F.Cu")
		(at 125.186948 -356.244906 90)
		(property "Reference" "C353"
			(at 0 0 90)
			(layer "F.SilkS")
			(hide yes)
			(effects
				(font
					(size 1.27 1.27)
				)
			)
		)
		(property "Value" ""
			(at 0 0 90)
			(layer "F.Fab")
			(effects
				(font
					(size 1.27 1.27)
				)
			)
		)
		(duplicate_pad_numbers_are_jumpers no)
		(fp_line
			(start 0.299974 -0.150114)
			(end 0.299974 0.150114)
			(stroke
				(width 0.1)
				(type default)
			)
			(layer "F.Fab")
		)
		(fp_line
			(start -0.299974 -0.150114)
			(end 0.299974 -0.150114)
			(stroke
				(width 0.1)
				(type default)
			)
			(layer "F.Fab")
		)
		(fp_line
			(start 0.299974 0.150114)
			(end -0.299974 0.150114)
			(stroke
				(width 0.1)
				(type default)
			)
			(layer "F.Fab")
		)
		(fp_line
			(start -0.299974 0.150114)
			(end -0.299974 -0.150114)
			(stroke
				(width 0.1)
				(type default)
			)
			(layer "F.Fab")
		)
		(pad "1" smd rect
			(at -0.2667 0 90)
			(size 0.3048 0.381)
			(layers "F.Cu" "F.Mask" "F.Paste")
			(net "P5E_PEX1_STN6_TX_DN<105>")
		)
		(pad "2" smd rect
			(at 0.2667 0 90)
			(size 0.3048 0.381)
			(layers "F.Cu" "F.Mask" "F.Paste")
			(net "P5E_PEX1_STN6_TX_C_DN<105>")
		)
	)
)
